G04 ================== begin FILE IDENTIFICATION RECORD ==================*
G04 Layout Name:  t6mg_pdb_a_v02_0109_1330.brd*
G04 Film Name:    pmt*
G04 File Format:  Gerber RS274X*
G04 File Origin:  Cadence Allegro 16.3-S038*
G04 Origin Date:  Mon Jan 13 14:11:53 2014*
G04 *
G04 Layer:  VIA CLASS/PASTEMASK_TOP*
G04 Layer:  PIN/PASTEMASK_TOP*
G04 Layer:  PACKAGE GEOMETRY/PASTEMASK_TOP*
G04 Layer:  MANUFACTURING/PHOTOPLOT_OUTLINE*
G04 Layer:  DRAWING FORMAT/TITLE_BLOCK*
G04 Layer:  DRAWING FORMAT/TITLE_DATA_PMT*
G04 *
G04 Offset:    (0.00 0.00)*
G04 Mirror:    No*
G04 Mode:      Positive*
G04 Rotation:  0*
G04 FullContactRelief:  No*
G04 UndefLineWidth:     6.00*
G04 ================== end FILE IDENTIFICATION RECORD ====================*
%FSLAX25Y25*MOIN*%
%IR0*IPPOS*OFA0.00000B0.00000*MIA0B0*SFA1.00000B1.00000*%
%ADD17C,.03*%
%ADD13C,.052*%
%ADD10C,.063*%
%ADD28C,.064*%
%ADD19C,.055*%
%ADD23C,.039*%
%ADD16C,.093*%
%ADD21R,.052X.052*%
%ADD15C,.077*%
%ADD11R,.063X.063*%
%ADD29R,.064X.064*%
%ADD20R,.055X.055*%
%ADD18R,.077X.077*%
%ADD12R,.02X.018*%
%ADD14R,.018X.02*%
%ADD24R,.05X.035*%
%ADD27R,.032X.028*%
%ADD30R,.028X.032*%
%ADD25R,.044X.054*%
%ADD22R,.068X.022*%
%ADD26R,.022X.068*%
%ADD31C,.006*%
G75*
%LPD*%
G75*
G54D10*
X22756Y113818D03*
X22480Y316838D03*
Y328649D03*
X22756Y1866819D03*
Y1948818D03*
Y2023818D03*
G54D20*
X54979Y70500D03*
Y206500D03*
Y279500D03*
Y415500D03*
X203542Y73105D03*
X204069Y152050D03*
X204137Y247568D03*
X204597Y331786D03*
X203541Y421732D03*
X204333Y506517D03*
X206668Y598130D03*
X204596Y681645D03*
X205626Y774526D03*
X205386Y856244D03*
X210091Y947202D03*
X209296Y1032544D03*
X205030Y1122856D03*
X205122Y1206233D03*
X205626Y1299104D03*
X204332Y1380966D03*
X203243Y1474162D03*
X204859Y1557277D03*
X205923Y1648177D03*
X205387Y1731351D03*
X205310Y1823227D03*
X204069Y1900420D03*
X205905Y1998730D03*
X205310Y2043388D03*
G54D11*
X22756Y125629D03*
X22480Y340460D03*
X22756Y1878630D03*
Y1960629D03*
Y2035629D03*
G54D30*
X271547Y250964D03*
Y256764D03*
X281569Y426540D03*
Y432340D03*
X285348Y601162D03*
Y606962D03*
X273114Y776236D03*
Y782036D03*
X285966Y949961D03*
Y955761D03*
X282958Y1124951D03*
Y1130751D03*
X283808Y1299622D03*
Y1305422D03*
X270234Y1473162D03*
Y1478962D03*
X284086Y1649843D03*
Y1655643D03*
X281066Y1824071D03*
Y1829871D03*
X294483Y72918D03*
Y78718D03*
X314562Y1998607D03*
Y2004407D03*
G54D12*
X13441Y501915D03*
Y498765D03*
X10914Y576211D03*
Y573061D03*
X15984Y576277D03*
Y573127D03*
X11153Y1635435D03*
Y1632285D03*
X16552Y1635303D03*
Y1632153D03*
X58752Y1302746D03*
Y1299596D03*
X50331Y1302680D03*
Y1299530D03*
X71909Y1302580D03*
Y1299430D03*
X67568Y1302581D03*
Y1299431D03*
X63061Y1302746D03*
Y1299596D03*
X54543Y1302681D03*
Y1299531D03*
X52227Y1341972D03*
Y1338822D03*
X88681Y701593D03*
Y698443D03*
X92860D03*
Y701593D03*
X80269D03*
Y698443D03*
X84533D03*
Y701593D03*
X84417Y1754902D03*
Y1758052D03*
X88624D03*
Y1754902D03*
X80349D03*
Y1758052D03*
X107268Y78205D03*
X107263Y75055D03*
Y78205D03*
X107268Y81355D03*
X107668Y429254D03*
Y426104D03*
Y422954D03*
Y426104D03*
X107615Y777299D03*
Y774149D03*
X107617Y771001D03*
Y774151D03*
X108819Y1119015D03*
X108816Y1125313D03*
Y1122163D03*
X108819Y1122165D03*
X108573Y1473357D03*
Y1470207D03*
X108574Y1467057D03*
Y1470207D03*
X108819Y1818228D03*
Y1815078D03*
Y1818228D03*
Y1821378D03*
X155370Y91281D03*
Y88131D03*
X155366Y85017D03*
Y88167D03*
X156321Y418198D03*
Y415048D03*
X161256Y418195D03*
Y415045D03*
X155351Y439268D03*
Y436118D03*
X155348Y432969D03*
Y436119D03*
X155356Y780982D03*
X155362Y787280D03*
Y784130D03*
X155356Y784132D03*
X156117Y1116127D03*
Y1112977D03*
X160870Y1116135D03*
Y1112985D03*
X155264Y1135344D03*
Y1132194D03*
X155263Y1129045D03*
Y1132195D03*
X155834Y1480274D03*
X155816Y1477124D03*
Y1480274D03*
X155834Y1483424D03*
X155570Y1831380D03*
Y1828230D03*
X155561Y1825087D03*
Y1828237D03*
X263086Y151264D03*
X267420D03*
X263086Y154414D03*
X267420D03*
X264516Y500919D03*
Y504069D03*
X264181Y851243D03*
Y854393D03*
X267194Y1195314D03*
Y1198464D03*
X262559Y1195314D03*
Y1198464D03*
X271943Y151264D03*
X276523D03*
X271943Y154414D03*
X276523D03*
X276617Y253439D03*
Y250289D03*
X281193Y253439D03*
Y250289D03*
X281074Y326517D03*
Y329667D03*
X289895Y326517D03*
Y329667D03*
X285513Y326517D03*
Y329667D03*
X291002Y429015D03*
Y425865D03*
X286665Y429015D03*
Y425865D03*
X273405Y500919D03*
Y504069D03*
X268938Y500919D03*
Y504069D03*
X277776Y500919D03*
Y504069D03*
X290984Y603637D03*
Y600487D03*
X283340Y676124D03*
Y679274D03*
X278955Y676124D03*
Y679274D03*
X274514Y676124D03*
Y679274D03*
X270109Y676124D03*
Y679274D03*
X278184Y778711D03*
Y775561D03*
X282737Y778711D03*
Y775561D03*
X277788Y851243D03*
X273305D03*
X268686D03*
X277788Y854393D03*
X273305D03*
X268686D03*
X291194Y949286D03*
Y952436D03*
X290107Y1019882D03*
X285666D03*
X281124D03*
X290107Y1023032D03*
X285666D03*
X281124D03*
X288188Y1127426D03*
Y1124276D03*
X276807Y1195314D03*
Y1198464D03*
X272082Y1195314D03*
Y1198464D03*
X289210Y1302097D03*
Y1298947D03*
X284240Y1378342D03*
Y1381492D03*
X279518Y1378341D03*
Y1381491D03*
X275052Y1378341D03*
Y1381491D03*
X270579Y1378341D03*
Y1381491D03*
X275521Y1475637D03*
Y1472487D03*
X279990Y1475637D03*
Y1472487D03*
X291054Y1547451D03*
Y1550601D03*
X289421Y1649168D03*
Y1652318D03*
X289499Y1726915D03*
Y1730065D03*
X284583Y1726915D03*
Y1730065D03*
X274704Y1726915D03*
Y1730065D03*
X279703Y1726915D03*
Y1730065D03*
X286623Y1826546D03*
Y1823396D03*
X291550Y1826546D03*
Y1823396D03*
X287121Y1901895D03*
Y1905045D03*
X282717Y1901895D03*
Y1905045D03*
X278262Y1901895D03*
Y1905045D03*
X273817Y1901895D03*
Y1905045D03*
X304151Y75393D03*
Y72243D03*
X308651Y75393D03*
Y72243D03*
X313089Y75393D03*
Y72243D03*
X299687Y75393D03*
Y72243D03*
X294506Y326517D03*
Y329667D03*
X295509Y603637D03*
Y600487D03*
X295874Y949286D03*
Y952436D03*
X294617Y1019882D03*
Y1023032D03*
X292698Y1127426D03*
Y1124276D03*
X294133Y1302097D03*
Y1298947D03*
X304870Y1547451D03*
Y1550601D03*
X295675Y1547451D03*
Y1550601D03*
X300392Y1547451D03*
Y1550601D03*
X294090Y1649168D03*
Y1652318D03*
X317567Y75393D03*
Y72243D03*
X322005Y75393D03*
Y72243D03*
X320045Y2002031D03*
Y1998881D03*
X324803Y2002031D03*
Y1998881D03*
G54D21*
X55254Y554500D03*
Y1612504D03*
G54D31*
G01X-723776Y2987387D02*
Y-376795D01*
Y-489221D01*
X1782976D01*
Y-376795D01*
Y2987387D01*
X-723776D01*
G01X-4000Y-62500D02*
Y-137500D01*
X496000D01*
Y-62500D01*
X-4000D01*
G01X8000Y-127500D02*
Y-132500D01*
G01X6543Y-127500D02*
X9457D01*
G01X14367Y-132500D02*
X11833D01*
Y-127500D01*
X14367D01*
G01X13353Y-129917D02*
X11833D01*
G01X16933Y-127500D02*
Y-132500D01*
X19467D01*
G01X23300Y-132667D02*
X23173Y-132583D01*
Y-132417D01*
X23300Y-132333D01*
X23427Y-132417D01*
Y-132583D01*
X23300Y-132667D01*
G01Y-130417D02*
X23173Y-130333D01*
Y-130167D01*
X23300Y-130083D01*
X23427Y-130167D01*
Y-130333D01*
X23300Y-130417D01*
G01X28083Y-134167D02*
X27450Y-133333D01*
X27133Y-132500D01*
Y-129167D01*
X27450Y-128333D01*
X28083Y-127500D01*
G01X33500D02*
X32993Y-127667D01*
X32613Y-128083D01*
X32360Y-128583D01*
X32170Y-129250D01*
X32107Y-130000D01*
X32170Y-130750D01*
X32360Y-131417D01*
X32613Y-131917D01*
X32993Y-132333D01*
X33500Y-132500D01*
X34007Y-132333D01*
X34387Y-131917D01*
X34640Y-131417D01*
X34830Y-130750D01*
X34893Y-130000D01*
X34830Y-129250D01*
X34640Y-128583D01*
X34387Y-128083D01*
X34007Y-127667D01*
X33500Y-127500D01*
G01X37207Y-131500D02*
X37587Y-132083D01*
X38093Y-132417D01*
X38663Y-132500D01*
X39170Y-132417D01*
X39677Y-132000D01*
X39993Y-131500D01*
X40057Y-131000D01*
X39930Y-130417D01*
X39487Y-130000D01*
X39043Y-129833D01*
X38473D01*
G01X39043D02*
X39423Y-129583D01*
X39740Y-129167D01*
X39867Y-128667D01*
X39740Y-128167D01*
X39423Y-127750D01*
X38853Y-127500D01*
X38283Y-127583D01*
X37713Y-127917D01*
G01X44017Y-134167D02*
X44650Y-133333D01*
X44967Y-132500D01*
Y-129167D01*
X44650Y-128333D01*
X44017Y-127500D01*
G01X47407Y-131500D02*
X47787Y-132083D01*
X48293Y-132417D01*
X48863Y-132500D01*
X49370Y-132417D01*
X49877Y-132000D01*
X50193Y-131500D01*
X50257Y-131000D01*
X50130Y-130417D01*
X49687Y-130000D01*
X49243Y-129833D01*
X48673D01*
G01X49243D02*
X49623Y-129583D01*
X49940Y-129167D01*
X50067Y-128667D01*
X49940Y-128167D01*
X49623Y-127750D01*
X49053Y-127500D01*
X48483Y-127583D01*
X47913Y-127917D01*
G01X52697Y-128333D02*
X53077Y-127833D01*
X53520Y-127583D01*
X54027Y-127500D01*
X54660Y-127667D01*
X55103Y-128083D01*
X55230Y-128583D01*
X55167Y-129083D01*
X54913Y-129500D01*
X53647Y-130333D01*
X53077Y-130917D01*
X52697Y-131750D01*
X52570Y-132500D01*
X55230D01*
G01X58873D02*
X59000Y-131417D01*
X59190Y-130500D01*
X59443Y-129667D01*
X59760Y-128750D01*
X60267Y-127500D01*
X57733D01*
G01X63277Y-130833D02*
X64923D01*
G01X67997Y-128333D02*
X68377Y-127833D01*
X68820Y-127583D01*
X69327Y-127500D01*
X69960Y-127667D01*
X70403Y-128083D01*
X70530Y-128583D01*
X70467Y-129083D01*
X70213Y-129500D01*
X68947Y-130333D01*
X68377Y-130917D01*
X67997Y-131750D01*
X67870Y-132500D01*
X70530D01*
G01X72907Y-131500D02*
X73287Y-132083D01*
X73793Y-132417D01*
X74363Y-132500D01*
X74870Y-132417D01*
X75377Y-132000D01*
X75693Y-131500D01*
X75757Y-131000D01*
X75630Y-130417D01*
X75187Y-130000D01*
X74743Y-129833D01*
X74173D01*
G01X74743D02*
X75123Y-129583D01*
X75440Y-129167D01*
X75567Y-128667D01*
X75440Y-128167D01*
X75123Y-127750D01*
X74553Y-127500D01*
X73983Y-127583D01*
X73413Y-127917D01*
G01X80160Y-132500D02*
Y-127500D01*
X77817Y-131083D01*
X80983D01*
G01X83107Y-131750D02*
X83487Y-132167D01*
X83930Y-132417D01*
X84500Y-132500D01*
X85070Y-132333D01*
X85513Y-132000D01*
X85830Y-131417D01*
X85893Y-130750D01*
X85767Y-130083D01*
X85450Y-129667D01*
X85007Y-129333D01*
X84563Y-129250D01*
X84120Y-129333D01*
X83550Y-129667D01*
X83740Y-127500D01*
X85450D01*
G01X93497Y-132500D02*
Y-127500D01*
X95903D01*
G01X95017Y-129917D02*
X93497D01*
G01X98217Y-132500D02*
X99800Y-127500D01*
X101383Y-132500D01*
G01X100813Y-130750D02*
X98787D01*
G01X103570Y-132500D02*
X106230Y-127500D01*
G01X103570D02*
X106230Y-132500D01*
G01X110000Y-132667D02*
X109873Y-132583D01*
Y-132417D01*
X110000Y-132333D01*
X110127Y-132417D01*
Y-132583D01*
X110000Y-132667D01*
G01Y-130417D02*
X109873Y-130333D01*
Y-130167D01*
X110000Y-130083D01*
X110127Y-130167D01*
Y-130333D01*
X110000Y-130417D01*
G01X114783Y-134167D02*
X114150Y-133333D01*
X113833Y-132500D01*
Y-129167D01*
X114150Y-128333D01*
X114783Y-127500D01*
G01X120200D02*
X119693Y-127667D01*
X119313Y-128083D01*
X119060Y-128583D01*
X118870Y-129250D01*
X118807Y-130000D01*
X118870Y-130750D01*
X119060Y-131417D01*
X119313Y-131917D01*
X119693Y-132333D01*
X120200Y-132500D01*
X120707Y-132333D01*
X121087Y-131917D01*
X121340Y-131417D01*
X121530Y-130750D01*
X121593Y-130000D01*
X121530Y-129250D01*
X121340Y-128583D01*
X121087Y-128083D01*
X120707Y-127667D01*
X120200Y-127500D01*
G01X123907Y-131500D02*
X124287Y-132083D01*
X124793Y-132417D01*
X125363Y-132500D01*
X125870Y-132417D01*
X126377Y-132000D01*
X126693Y-131500D01*
X126757Y-131000D01*
X126630Y-130417D01*
X126187Y-130000D01*
X125743Y-129833D01*
X125173D01*
G01X125743D02*
X126123Y-129583D01*
X126440Y-129167D01*
X126567Y-128667D01*
X126440Y-128167D01*
X126123Y-127750D01*
X125553Y-127500D01*
X124983Y-127583D01*
X124413Y-127917D01*
G01X130717Y-134167D02*
X131350Y-133333D01*
X131667Y-132500D01*
Y-129167D01*
X131350Y-128333D01*
X130717Y-127500D01*
G01X134107Y-131500D02*
X134487Y-132083D01*
X134993Y-132417D01*
X135563Y-132500D01*
X136070Y-132417D01*
X136577Y-132000D01*
X136893Y-131500D01*
X136957Y-131000D01*
X136830Y-130417D01*
X136387Y-130000D01*
X135943Y-129833D01*
X135373D01*
G01X135943D02*
X136323Y-129583D01*
X136640Y-129167D01*
X136767Y-128667D01*
X136640Y-128167D01*
X136323Y-127750D01*
X135753Y-127500D01*
X135183Y-127583D01*
X134613Y-127917D01*
G01X139523Y-131917D02*
X139967Y-132333D01*
X140473Y-132500D01*
X140980Y-132333D01*
X141423Y-131833D01*
X141740Y-131083D01*
X141867Y-130333D01*
Y-129417D01*
X141740Y-128667D01*
X141423Y-128000D01*
X141043Y-127667D01*
X140600Y-127500D01*
X140093Y-127667D01*
X139713Y-128000D01*
X139460Y-128500D01*
X139333Y-129167D01*
X139460Y-129750D01*
X139777Y-130333D01*
X140157Y-130667D01*
X140600Y-130750D01*
X141107Y-130583D01*
X141487Y-130167D01*
X141867Y-129417D01*
G01X145573Y-132500D02*
X145700Y-131417D01*
X145890Y-130500D01*
X146143Y-129667D01*
X146460Y-128750D01*
X146967Y-127500D01*
X144433D01*
G01X149977Y-130833D02*
X151623D01*
G01X154507Y-131500D02*
X154887Y-132083D01*
X155393Y-132417D01*
X155963Y-132500D01*
X156470Y-132417D01*
X156977Y-132000D01*
X157293Y-131500D01*
X157357Y-131000D01*
X157230Y-130417D01*
X156787Y-130000D01*
X156343Y-129833D01*
X155773D01*
G01X156343D02*
X156723Y-129583D01*
X157040Y-129167D01*
X157167Y-128667D01*
X157040Y-128167D01*
X156723Y-127750D01*
X156153Y-127500D01*
X155583Y-127583D01*
X155013Y-127917D01*
G01X159797Y-130417D02*
X160240Y-129833D01*
X160620Y-129500D01*
X161127Y-129333D01*
X161570Y-129500D01*
X161887Y-129833D01*
X162140Y-130333D01*
X162203Y-130917D01*
X162140Y-131417D01*
X161887Y-131917D01*
X161507Y-132333D01*
X161063Y-132500D01*
X160557Y-132333D01*
X160113Y-131833D01*
X159860Y-131083D01*
X159797Y-130250D01*
X159923Y-129167D01*
X160113Y-128583D01*
X160430Y-128000D01*
X160873Y-127583D01*
X161317Y-127500D01*
X161760Y-127667D01*
X162077Y-128083D01*
G01X166100Y-132500D02*
Y-127500D01*
X165340Y-128500D01*
G01Y-132500D02*
X166860D01*
G01X171960D02*
Y-127500D01*
X169617Y-131083D01*
X172783D01*
G01X191000Y-62500D02*
Y-137500D01*
G01Y-112500D02*
X294000D01*
Y-87500D01*
G01X191000D02*
X294000D01*
G01X301507Y-122500D02*
Y-117500D01*
X302773D01*
X303280Y-117750D01*
X303660Y-118083D01*
X303977Y-118583D01*
X304230Y-119167D01*
X304293Y-120000D01*
X304230Y-120833D01*
X303977Y-121417D01*
X303660Y-121917D01*
X303280Y-122250D01*
X302773Y-122500D01*
X301507D01*
G01X306417D02*
X308000Y-117500D01*
X309583Y-122500D01*
G01X309013Y-120750D02*
X306987D01*
G01X313100Y-117500D02*
Y-122500D01*
G01X311643Y-117500D02*
X314557D01*
G01X319467Y-122500D02*
X316933D01*
Y-117500D01*
X319467D01*
G01X318453Y-119917D02*
X316933D01*
G01X323300Y-122667D02*
X323173Y-122583D01*
Y-122417D01*
X323300Y-122333D01*
X323427Y-122417D01*
Y-122583D01*
X323300Y-122667D01*
G01Y-120417D02*
X323173Y-120333D01*
Y-120167D01*
X323300Y-120083D01*
X323427Y-120167D01*
Y-120333D01*
X323300Y-120417D01*
G01X296000Y-62500D02*
Y-137500D01*
G01X294000Y-62500D02*
Y-137500D01*
G01X301633Y-97500D02*
Y-92500D01*
X303153D01*
X303660Y-92750D01*
X304040Y-93333D01*
X304167Y-94000D01*
X304040Y-94667D01*
X303723Y-95167D01*
X303153Y-95417D01*
X301633D01*
G01X306860Y-97667D02*
X309140Y-92500D01*
G01X311643Y-97500D02*
Y-92500D01*
X314557Y-97500D01*
Y-92500D01*
G01X318200Y-97667D02*
X318073Y-97583D01*
Y-97417D01*
X318200Y-97333D01*
X318327Y-97417D01*
Y-97583D01*
X318200Y-97667D01*
G01Y-95417D02*
X318073Y-95333D01*
Y-95167D01*
X318200Y-95083D01*
X318327Y-95167D01*
Y-95333D01*
X318200Y-95417D01*
G01X296000Y-112500D02*
X496000D01*
G01X301633Y-72500D02*
Y-67500D01*
X303153D01*
X303660Y-67750D01*
X304040Y-68333D01*
X304167Y-69000D01*
X304040Y-69667D01*
X303723Y-70167D01*
X303153Y-70417D01*
X301633D01*
G01X306733Y-72500D02*
Y-67500D01*
X308317D01*
X308823Y-67750D01*
X309140Y-68083D01*
X309267Y-68750D01*
X309140Y-69417D01*
X308760Y-69833D01*
X308317Y-70083D01*
X306733D01*
G01X308317D02*
X309267Y-72500D01*
G01X313100D02*
X312593Y-72417D01*
X312150Y-72083D01*
X311770Y-71583D01*
X311517Y-71000D01*
X311390Y-70333D01*
Y-69667D01*
X311517Y-69000D01*
X311770Y-68417D01*
X312150Y-67917D01*
X312593Y-67583D01*
X313100Y-67500D01*
X313607Y-67583D01*
X314050Y-67917D01*
X314430Y-68417D01*
X314683Y-69000D01*
X314810Y-69667D01*
Y-70333D01*
X314683Y-71000D01*
X314430Y-71583D01*
X314050Y-72083D01*
X313607Y-72417D01*
X313100Y-72500D01*
G01X316933Y-71500D02*
X317250Y-72000D01*
X317630Y-72333D01*
X318073Y-72500D01*
X318580Y-72333D01*
X318960Y-72000D01*
X319340Y-71500D01*
X319467Y-70833D01*
Y-67500D01*
G01X324567Y-72500D02*
X322033D01*
Y-67500D01*
X324567D01*
G01X323553Y-69917D02*
X322033D01*
G01X329793Y-67917D02*
X329413Y-67667D01*
X328970Y-67500D01*
X328463D01*
X327893Y-67750D01*
X327450Y-68167D01*
X327133Y-68667D01*
X326880Y-69500D01*
X326817Y-70250D01*
X326943Y-71000D01*
X327133Y-71500D01*
X327513Y-72000D01*
X327957Y-72333D01*
X328400Y-72500D01*
X328843D01*
X329287Y-72333D01*
X329667Y-72083D01*
X329983Y-71750D01*
G01X333500Y-67500D02*
Y-72500D01*
G01X332043Y-67500D02*
X334957D01*
G01X338600Y-72667D02*
X338473Y-72583D01*
Y-72417D01*
X338600Y-72333D01*
X338727Y-72417D01*
Y-72583D01*
X338600Y-72667D01*
G01Y-70417D02*
X338473Y-70333D01*
Y-70167D01*
X338600Y-70083D01*
X338727Y-70167D01*
Y-70333D01*
X338600Y-70417D01*
G01X296000Y-87500D02*
X496000D01*
G01X411000Y-112500D02*
Y-137500D01*
G01X416633Y-122500D02*
Y-117500D01*
X418217D01*
X418723Y-117750D01*
X419040Y-118083D01*
X419167Y-118750D01*
X419040Y-119417D01*
X418660Y-119833D01*
X418217Y-120083D01*
X416633D01*
G01X418217D02*
X419167Y-122500D01*
G01X424267D02*
X421733D01*
Y-117500D01*
X424267D01*
G01X423253Y-119917D02*
X421733D01*
G01X426517Y-117500D02*
X428100Y-122500D01*
X429683Y-117500D01*
G01X433200Y-122667D02*
X433073Y-122583D01*
Y-122417D01*
X433200Y-122333D01*
X433327Y-122417D01*
Y-122583D01*
X433200Y-122667D01*
G01Y-120417D02*
X433073Y-120333D01*
Y-120167D01*
X433200Y-120083D01*
X433327Y-120167D01*
Y-120333D01*
X433200Y-120417D01*
G01X460000Y-112500D02*
Y-137500D01*
G01X-723776Y2987387D02*
Y-376795D01*
Y-489221D01*
X1782976D01*
Y-376795D01*
Y2987387D01*
X-723776D01*
G01X6705Y-124160D02*
X7332Y-124685D01*
X8037Y-125000D01*
X8663D01*
X9290Y-124685D01*
X9760Y-124160D01*
X9995Y-123425D01*
X9838Y-122690D01*
X9447Y-122060D01*
X8742Y-121640D01*
X7802Y-121430D01*
X7253Y-121010D01*
X7018Y-120275D01*
X7175Y-119540D01*
X7567Y-119015D01*
X8115Y-118700D01*
X8663D01*
X9212Y-118910D01*
X9682Y-119435D01*
G01X13005Y-125000D02*
Y-118700D01*
G01X16295D02*
Y-125000D01*
G01Y-121850D02*
X13005D01*
G01X20010Y-118700D02*
X21890D01*
G01X20950D02*
Y-125000D01*
G01X20010D02*
X21890D01*
G01X28817D02*
X25683D01*
Y-118700D01*
X28817D01*
G01X27563Y-121745D02*
X25683D01*
G01X31748Y-125000D02*
Y-118700D01*
X35352Y-125000D01*
Y-118700D01*
G01X39693Y-126155D02*
X40007Y-124790D01*
G01X46150Y-118700D02*
Y-125000D01*
G01X44348Y-118700D02*
X47952D01*
G01X50492Y-125000D02*
X52450Y-118700D01*
X54408Y-125000D01*
G01X53703Y-122795D02*
X51197D01*
G01X57810Y-118700D02*
X59690D01*
G01X58750D02*
Y-125000D01*
G01X57810D02*
X59690D01*
G01X62700Y-118700D02*
X63797Y-125000D01*
X65050Y-118700D01*
X66303Y-125000D01*
X67400Y-118700D01*
G01X69392Y-125000D02*
X71350Y-118700D01*
X73308Y-125000D01*
G01X72603Y-122795D02*
X70097D01*
G01X75848Y-125000D02*
Y-118700D01*
X79452Y-125000D01*
Y-118700D01*
G01X88683Y-125000D02*
Y-118700D01*
X90642D01*
X91268Y-119015D01*
X91660Y-119435D01*
X91817Y-120275D01*
X91660Y-121115D01*
X91190Y-121640D01*
X90642Y-121955D01*
X88683D01*
G01X90642D02*
X91817Y-125000D01*
G01X96550Y-125210D02*
X96393Y-125105D01*
Y-124895D01*
X96550Y-124790D01*
X96707Y-124895D01*
Y-125105D01*
X96550Y-125210D01*
G01X102850Y-125000D02*
X102223Y-124895D01*
X101675Y-124475D01*
X101205Y-123845D01*
X100892Y-123110D01*
X100735Y-122270D01*
Y-121430D01*
X100892Y-120590D01*
X101205Y-119855D01*
X101675Y-119225D01*
X102223Y-118805D01*
X102850Y-118700D01*
X103477Y-118805D01*
X104025Y-119225D01*
X104495Y-119855D01*
X104808Y-120590D01*
X104965Y-121430D01*
Y-122270D01*
X104808Y-123110D01*
X104495Y-123845D01*
X104025Y-124475D01*
X103477Y-124895D01*
X102850Y-125000D01*
G01X109150Y-125210D02*
X108993Y-125105D01*
Y-124895D01*
X109150Y-124790D01*
X109307Y-124895D01*
Y-125105D01*
X109150Y-125210D01*
G01X117173Y-119225D02*
X116703Y-118910D01*
X116155Y-118700D01*
X115528D01*
X114823Y-119015D01*
X114275Y-119540D01*
X113883Y-120170D01*
X113570Y-121220D01*
X113492Y-122165D01*
X113648Y-123110D01*
X113883Y-123740D01*
X114353Y-124370D01*
X114902Y-124790D01*
X115450Y-125000D01*
X115998D01*
X116547Y-124790D01*
X117017Y-124475D01*
X117408Y-124055D01*
G01X121750Y-125210D02*
X121593Y-125105D01*
Y-124895D01*
X121750Y-124790D01*
X121907Y-124895D01*
Y-125105D01*
X121750Y-125210D01*
G01X6627Y-115000D02*
Y-108700D01*
G01X9603D02*
X6627Y-112585D01*
G01X10073Y-115000D02*
X7958Y-110800D01*
G01X12927Y-108700D02*
Y-113215D01*
X13240Y-114160D01*
X13867Y-114790D01*
X14650Y-115000D01*
X15433Y-114790D01*
X16060Y-114160D01*
X16373Y-113215D01*
Y-108700D01*
G01X22517Y-115000D02*
X19383D01*
Y-108700D01*
X22517D01*
G01X21263Y-111745D02*
X19383D01*
G01X26310Y-108700D02*
X28190D01*
G01X27250D02*
Y-115000D01*
G01X26310D02*
X28190D01*
G01X38205Y-114160D02*
X38832Y-114685D01*
X39537Y-115000D01*
X40163D01*
X40790Y-114685D01*
X41260Y-114160D01*
X41495Y-113425D01*
X41338Y-112690D01*
X40947Y-112060D01*
X40242Y-111640D01*
X39302Y-111430D01*
X38753Y-111010D01*
X38518Y-110275D01*
X38675Y-109540D01*
X39067Y-109015D01*
X39615Y-108700D01*
X40163D01*
X40712Y-108910D01*
X41182Y-109435D01*
G01X44505Y-115000D02*
Y-108700D01*
G01X47795D02*
Y-115000D01*
G01Y-111850D02*
X44505D01*
G01X50492Y-115000D02*
X52450Y-108700D01*
X54408Y-115000D01*
G01X53703Y-112795D02*
X51197D01*
G01X56948Y-115000D02*
Y-108700D01*
X60552Y-115000D01*
Y-108700D01*
G01X69705Y-115000D02*
Y-108700D01*
G01X72995D02*
Y-115000D01*
G01Y-111850D02*
X69705D01*
G01X76005Y-114160D02*
X76632Y-114685D01*
X77337Y-115000D01*
X77963D01*
X78590Y-114685D01*
X79060Y-114160D01*
X79295Y-113425D01*
X79138Y-112690D01*
X78747Y-112060D01*
X78042Y-111640D01*
X77102Y-111430D01*
X76553Y-111010D01*
X76318Y-110275D01*
X76475Y-109540D01*
X76867Y-109015D01*
X77415Y-108700D01*
X77963D01*
X78512Y-108910D01*
X78982Y-109435D01*
G01X83010Y-108700D02*
X84890D01*
G01X83950D02*
Y-115000D01*
G01X83010D02*
X84890D01*
G01X88292D02*
X90250Y-108700D01*
X92208Y-115000D01*
G01X91503Y-112795D02*
X88997D01*
G01X94748Y-115000D02*
Y-108700D01*
X98352Y-115000D01*
Y-108700D01*
G01X103320Y-111850D02*
X104887D01*
Y-113740D01*
X104417Y-114370D01*
X103868Y-114790D01*
X103085Y-115000D01*
X102302Y-114790D01*
X101753Y-114370D01*
X101283Y-113740D01*
X100970Y-113005D01*
X100813Y-112165D01*
Y-111430D01*
X100970Y-110800D01*
X101283Y-110065D01*
X101753Y-109435D01*
X102223Y-109015D01*
X102850Y-108700D01*
X103398D01*
X104025Y-108910D01*
X104495Y-109330D01*
G01X108993Y-116155D02*
X109307Y-114790D01*
G01X115450Y-108700D02*
Y-115000D01*
G01X113648Y-108700D02*
X117252D01*
G01X119792Y-115000D02*
X121750Y-108700D01*
X123708Y-115000D01*
G01X123003Y-112795D02*
X120497D01*
G01X128050Y-115000D02*
X127423Y-114895D01*
X126875Y-114475D01*
X126405Y-113845D01*
X126092Y-113110D01*
X125935Y-112270D01*
Y-111430D01*
X126092Y-110590D01*
X126405Y-109855D01*
X126875Y-109225D01*
X127423Y-108805D01*
X128050Y-108700D01*
X128677Y-108805D01*
X129225Y-109225D01*
X129695Y-109855D01*
X130008Y-110590D01*
X130165Y-111430D01*
Y-112270D01*
X130008Y-113110D01*
X129695Y-113845D01*
X129225Y-114475D01*
X128677Y-114895D01*
X128050Y-115000D01*
G01X140650D02*
Y-112165D01*
X139083Y-108700D01*
G01X142217D02*
X140650Y-112165D01*
G01X145227Y-108700D02*
Y-113215D01*
X145540Y-114160D01*
X146167Y-114790D01*
X146950Y-115000D01*
X147733Y-114790D01*
X148360Y-114160D01*
X148673Y-113215D01*
Y-108700D01*
G01X151292Y-115000D02*
X153250Y-108700D01*
X155208Y-115000D01*
G01X154503Y-112795D02*
X151997D01*
G01X157748Y-115000D02*
Y-108700D01*
X161352Y-115000D01*
Y-108700D01*
G01X30650Y-92300D02*
X28130Y-91883D01*
X25925Y-90217D01*
X24035Y-87717D01*
X22775Y-84800D01*
X22145Y-81467D01*
Y-78133D01*
X22775Y-74800D01*
X24035Y-71883D01*
X25925Y-69384D01*
X28130Y-67717D01*
X30650Y-67300D01*
X33170Y-67717D01*
X35375Y-69384D01*
X37265Y-71883D01*
X38525Y-74800D01*
X39155Y-78133D01*
Y-81467D01*
X38525Y-84800D01*
X37265Y-87717D01*
X35375Y-90217D01*
X33170Y-91883D01*
X30650Y-92300D01*
G01X33170Y-85633D02*
X36950Y-92300D01*
G01X50495Y-75634D02*
Y-87300D01*
X51755Y-90217D01*
X53645Y-91883D01*
X55850Y-92300D01*
X58055Y-91883D01*
X59945Y-90217D01*
X61205Y-87300D01*
G01Y-92300D02*
Y-75634D01*
G01X86720Y-92300D02*
Y-75634D01*
G01Y-78550D02*
X85460Y-76884D01*
X83570Y-76050D01*
X81365Y-75634D01*
X79160Y-76467D01*
X77270Y-78133D01*
X76010Y-80634D01*
X75380Y-83967D01*
X76010Y-87300D01*
X77270Y-89801D01*
X79160Y-91467D01*
X81365Y-92300D01*
X83570Y-91883D01*
X85460Y-90634D01*
X86720Y-88967D01*
G01X100895Y-92300D02*
Y-75634D01*
G01Y-79800D02*
X102155Y-77717D01*
X104045Y-76050D01*
X106565Y-75634D01*
X108770Y-76050D01*
X110660Y-77717D01*
X111605Y-80634D01*
Y-92300D01*
G01X131450Y-67300D02*
Y-92300D01*
G01X127040Y-75634D02*
X135860D01*
G01X162320Y-92300D02*
Y-75634D01*
G01Y-78550D02*
X161060Y-76884D01*
X159170Y-76050D01*
X156965Y-75634D01*
X154760Y-76467D01*
X152870Y-78133D01*
X151610Y-80634D01*
X150980Y-83967D01*
X151610Y-87300D01*
X152870Y-89801D01*
X154760Y-91467D01*
X156965Y-92300D01*
X159170Y-91883D01*
X161060Y-90634D01*
X162320Y-88967D01*
G01X6548Y-105000D02*
Y-98700D01*
X10152Y-105000D01*
Y-98700D01*
G01X14650Y-105000D02*
X14023Y-104895D01*
X13475Y-104475D01*
X13005Y-103845D01*
X12692Y-103110D01*
X12535Y-102270D01*
Y-101430D01*
X12692Y-100590D01*
X13005Y-99855D01*
X13475Y-99225D01*
X14023Y-98805D01*
X14650Y-98700D01*
X15277Y-98805D01*
X15825Y-99225D01*
X16295Y-99855D01*
X16608Y-100590D01*
X16765Y-101430D01*
Y-102270D01*
X16608Y-103110D01*
X16295Y-103845D01*
X15825Y-104475D01*
X15277Y-104895D01*
X14650Y-105000D01*
G01X20950Y-105210D02*
X20793Y-105105D01*
Y-104895D01*
X20950Y-104790D01*
X21107Y-104895D01*
Y-105105D01*
X20950Y-105210D01*
G01X27250Y-105000D02*
Y-98700D01*
X26310Y-99960D01*
G01Y-105000D02*
X28190D01*
G01X33550D02*
X34098Y-104895D01*
X34725Y-104580D01*
X35117Y-104055D01*
X35273Y-103320D01*
X35117Y-102585D01*
X34647Y-101955D01*
X33942Y-101640D01*
X33158D01*
X32688Y-101430D01*
X32297Y-100905D01*
X32140Y-100170D01*
X32375Y-99435D01*
X32923Y-98910D01*
X33550Y-98700D01*
X34177Y-98910D01*
X34725Y-99435D01*
X34960Y-100170D01*
X34803Y-100905D01*
X34412Y-101430D01*
X33942Y-101640D01*
X33158D01*
X32453Y-101955D01*
X31983Y-102585D01*
X31827Y-103320D01*
X31983Y-104055D01*
X32375Y-104580D01*
X33002Y-104895D01*
X33550Y-105000D01*
G01X39850D02*
X40398Y-104895D01*
X41025Y-104580D01*
X41417Y-104055D01*
X41573Y-103320D01*
X41417Y-102585D01*
X40947Y-101955D01*
X40242Y-101640D01*
X39458D01*
X38988Y-101430D01*
X38597Y-100905D01*
X38440Y-100170D01*
X38675Y-99435D01*
X39223Y-98910D01*
X39850Y-98700D01*
X40477Y-98910D01*
X41025Y-99435D01*
X41260Y-100170D01*
X41103Y-100905D01*
X40712Y-101430D01*
X40242Y-101640D01*
X39458D01*
X38753Y-101955D01*
X38283Y-102585D01*
X38127Y-103320D01*
X38283Y-104055D01*
X38675Y-104580D01*
X39302Y-104895D01*
X39850Y-105000D01*
G01X45993Y-106155D02*
X46307Y-104790D01*
G01X50100Y-98700D02*
X51197Y-105000D01*
X52450Y-98700D01*
X53703Y-105000D01*
X54800Y-98700D01*
G01X60317Y-105000D02*
X57183D01*
Y-98700D01*
X60317D01*
G01X59063Y-101745D02*
X57183D01*
G01X63248Y-105000D02*
Y-98700D01*
X66852Y-105000D01*
Y-98700D01*
G01X76005Y-105000D02*
Y-98700D01*
G01X79295D02*
Y-105000D01*
G01Y-101850D02*
X76005D01*
G01X81600Y-98700D02*
X82697Y-105000D01*
X83950Y-98700D01*
X85203Y-105000D01*
X86300Y-98700D01*
G01X88292Y-105000D02*
X90250Y-98700D01*
X92208Y-105000D01*
G01X91503Y-102795D02*
X88997D01*
G01X101362Y-99750D02*
X101832Y-99120D01*
X102380Y-98805D01*
X103007Y-98700D01*
X103790Y-98910D01*
X104338Y-99435D01*
X104495Y-100065D01*
X104417Y-100695D01*
X104103Y-101220D01*
X102537Y-102270D01*
X101832Y-103005D01*
X101362Y-104055D01*
X101205Y-105000D01*
X104495D01*
G01X107348D02*
Y-98700D01*
X110952Y-105000D01*
Y-98700D01*
G01X113727Y-105000D02*
Y-98700D01*
X115293D01*
X115920Y-99015D01*
X116390Y-99435D01*
X116782Y-100065D01*
X117095Y-100800D01*
X117173Y-101850D01*
X117095Y-102900D01*
X116782Y-103635D01*
X116390Y-104265D01*
X115920Y-104685D01*
X115293Y-105000D01*
X113727D01*
G01X126483D02*
Y-98700D01*
X128442D01*
X129068Y-99015D01*
X129460Y-99435D01*
X129617Y-100275D01*
X129460Y-101115D01*
X128990Y-101640D01*
X128442Y-101955D01*
X126483D01*
G01X128442D02*
X129617Y-105000D01*
G01X132627D02*
Y-98700D01*
X134193D01*
X134820Y-99015D01*
X135290Y-99435D01*
X135682Y-100065D01*
X135995Y-100800D01*
X136073Y-101850D01*
X135995Y-102900D01*
X135682Y-103635D01*
X135290Y-104265D01*
X134820Y-104685D01*
X134193Y-105000D01*
X132627D01*
G01X140650Y-105210D02*
X140493Y-105105D01*
Y-104895D01*
X140650Y-104790D01*
X140807Y-104895D01*
Y-105105D01*
X140650Y-105210D01*
G01X213500Y-105000D02*
Y-97000D01*
X215900D01*
X216700Y-97400D01*
X217300Y-98333D01*
X217500Y-99400D01*
X217300Y-100467D01*
X216800Y-101267D01*
X215900Y-101667D01*
X213500D01*
G01X221000Y-105000D02*
X223500Y-97000D01*
X226000Y-105000D01*
G01X225100Y-102200D02*
X221900D01*
G01X229400Y-103934D02*
X230200Y-104600D01*
X231100Y-105000D01*
X231900D01*
X232700Y-104600D01*
X233300Y-103934D01*
X233600Y-103000D01*
X233400Y-102067D01*
X232900Y-101267D01*
X232000Y-100733D01*
X230800Y-100467D01*
X230100Y-99933D01*
X229800Y-99000D01*
X230000Y-98067D01*
X230500Y-97400D01*
X231200Y-97000D01*
X231900D01*
X232600Y-97267D01*
X233200Y-97933D01*
G01X239500Y-97000D02*
Y-105000D01*
G01X237200Y-97000D02*
X241800D01*
G01X246200Y-102333D02*
X248800D01*
G01X255500Y-97000D02*
Y-105000D01*
G01X253200Y-97000D02*
X257800D01*
G01X263500Y-105000D02*
X262700Y-104867D01*
X262000Y-104333D01*
X261400Y-103533D01*
X261000Y-102600D01*
X260800Y-101533D01*
Y-100467D01*
X261000Y-99400D01*
X261400Y-98467D01*
X262000Y-97667D01*
X262700Y-97133D01*
X263500Y-97000D01*
X264300Y-97133D01*
X265000Y-97667D01*
X265600Y-98467D01*
X266000Y-99400D01*
X266200Y-100467D01*
Y-101533D01*
X266000Y-102600D01*
X265600Y-103533D01*
X265000Y-104333D01*
X264300Y-104867D01*
X263500Y-105000D01*
G01X269500D02*
Y-97000D01*
X271900D01*
X272700Y-97400D01*
X273300Y-98333D01*
X273500Y-99400D01*
X273300Y-100467D01*
X272800Y-101267D01*
X271900Y-101667D01*
X269500D01*
G01X202000Y-72000D02*
Y-80000D01*
X206000D01*
G01X213800D02*
Y-74667D01*
G01Y-75600D02*
X213400Y-75067D01*
X212800Y-74800D01*
X212100Y-74667D01*
X211400Y-74933D01*
X210800Y-75467D01*
X210400Y-76267D01*
X210200Y-77333D01*
X210400Y-78400D01*
X210800Y-79200D01*
X211400Y-79733D01*
X212100Y-80000D01*
X212800Y-79867D01*
X213400Y-79467D01*
X213800Y-78934D01*
G01X217900Y-82400D02*
X218500Y-82667D01*
X219300Y-82400D01*
X219800Y-81867D01*
X220200Y-81200D01*
X220800Y-79067D01*
X222100Y-74667D01*
G01X218900D02*
X220800Y-79067D01*
G01X226500Y-76400D02*
X229700D01*
X229400Y-75467D01*
X228900Y-74933D01*
X228200Y-74667D01*
X227500Y-74800D01*
X226900Y-75200D01*
X226500Y-76133D01*
X226300Y-76934D01*
Y-77733D01*
X226500Y-78533D01*
X227000Y-79333D01*
X227600Y-79867D01*
X228300Y-80000D01*
X229000Y-79733D01*
X229700Y-78934D01*
G01X234600Y-80000D02*
Y-74667D01*
G01Y-75733D02*
X235100Y-75200D01*
X235600Y-74800D01*
X236300Y-74667D01*
X236800Y-74800D01*
X237400Y-75200D01*
G01X225500Y-122000D02*
Y-130000D01*
G01X223200Y-122000D02*
X227800D01*
G01X233500Y-124667D02*
Y-130000D01*
G01Y-122533D02*
X233300Y-122400D01*
Y-122133D01*
X233500Y-122000D01*
X233700Y-122133D01*
Y-122400D01*
X233500Y-122533D01*
G01X239800Y-130000D02*
Y-124667D01*
G01Y-126000D02*
X240200Y-125333D01*
X240800Y-124800D01*
X241600Y-124667D01*
X242300Y-124800D01*
X242900Y-125333D01*
X243200Y-126267D01*
Y-130000D01*
G01X251300D02*
Y-124667D01*
G01Y-125600D02*
X250900Y-125067D01*
X250300Y-124800D01*
X249600Y-124667D01*
X248900Y-124933D01*
X248300Y-125467D01*
X247900Y-126267D01*
X247700Y-127333D01*
X247900Y-128400D01*
X248300Y-129200D01*
X248900Y-129733D01*
X249600Y-130000D01*
X250300Y-129867D01*
X250900Y-129467D01*
X251300Y-128934D01*
G01X328600Y-123333D02*
X329200Y-122533D01*
X329900Y-122133D01*
X330700Y-122000D01*
X331700Y-122267D01*
X332400Y-122933D01*
X332600Y-123733D01*
X332500Y-124534D01*
X332100Y-125200D01*
X330100Y-126533D01*
X329200Y-127467D01*
X328600Y-128800D01*
X328400Y-130000D01*
X332600D01*
G01X338500Y-122000D02*
X337700Y-122267D01*
X337100Y-122933D01*
X336700Y-123733D01*
X336400Y-124800D01*
X336300Y-126000D01*
X336400Y-127200D01*
X336700Y-128267D01*
X337100Y-129067D01*
X337700Y-129733D01*
X338500Y-130000D01*
X339300Y-129733D01*
X339900Y-129067D01*
X340300Y-128267D01*
X340600Y-127200D01*
X340700Y-126000D01*
X340600Y-124800D01*
X340300Y-123733D01*
X339900Y-122933D01*
X339300Y-122267D01*
X338500Y-122000D01*
G01X346500Y-130000D02*
Y-122000D01*
X345300Y-123600D01*
G01Y-130000D02*
X347700D01*
G01X352300Y-128400D02*
X352900Y-129333D01*
X353700Y-129867D01*
X354600Y-130000D01*
X355400Y-129867D01*
X356200Y-129200D01*
X356700Y-128400D01*
X356800Y-127600D01*
X356600Y-126667D01*
X355900Y-126000D01*
X355200Y-125733D01*
X354300D01*
G01X355200D02*
X355800Y-125333D01*
X356300Y-124667D01*
X356500Y-123867D01*
X356300Y-123067D01*
X355800Y-122400D01*
X354900Y-122000D01*
X354000Y-122133D01*
X353100Y-122667D01*
G01X360700Y-130267D02*
X364300Y-122000D01*
G01X370500D02*
X369700Y-122267D01*
X369100Y-122933D01*
X368700Y-123733D01*
X368400Y-124800D01*
X368300Y-126000D01*
X368400Y-127200D01*
X368700Y-128267D01*
X369100Y-129067D01*
X369700Y-129733D01*
X370500Y-130000D01*
X371300Y-129733D01*
X371900Y-129067D01*
X372300Y-128267D01*
X372600Y-127200D01*
X372700Y-126000D01*
X372600Y-124800D01*
X372300Y-123733D01*
X371900Y-122933D01*
X371300Y-122267D01*
X370500Y-122000D01*
G01X378500Y-130000D02*
Y-122000D01*
X377300Y-123600D01*
G01Y-130000D02*
X379700D01*
G01X384700Y-130267D02*
X388300Y-122000D01*
G01X394500D02*
X393700Y-122267D01*
X393100Y-122933D01*
X392700Y-123733D01*
X392400Y-124800D01*
X392300Y-126000D01*
X392400Y-127200D01*
X392700Y-128267D01*
X393100Y-129067D01*
X393700Y-129733D01*
X394500Y-130000D01*
X395300Y-129733D01*
X395900Y-129067D01*
X396300Y-128267D01*
X396600Y-127200D01*
X396700Y-126000D01*
X396600Y-124800D01*
X396300Y-123733D01*
X395900Y-122933D01*
X395300Y-122267D01*
X394500Y-122000D01*
G01X400800Y-129067D02*
X401500Y-129733D01*
X402300Y-130000D01*
X403100Y-129733D01*
X403800Y-128934D01*
X404300Y-127733D01*
X404500Y-126533D01*
Y-125067D01*
X404300Y-123867D01*
X403800Y-122800D01*
X403200Y-122267D01*
X402500Y-122000D01*
X401700Y-122267D01*
X401100Y-122800D01*
X400700Y-123600D01*
X400500Y-124667D01*
X400700Y-125600D01*
X401200Y-126533D01*
X401800Y-127067D01*
X402500Y-127200D01*
X403300Y-126934D01*
X403900Y-126267D01*
X404500Y-125067D01*
G01X328300Y-105000D02*
Y-97000D01*
X330300D01*
X331100Y-97400D01*
X331700Y-97933D01*
X332200Y-98733D01*
X332600Y-99667D01*
X332700Y-101000D01*
X332600Y-102333D01*
X332200Y-103267D01*
X331700Y-104067D01*
X331100Y-104600D01*
X330300Y-105000D01*
X328300D01*
G01X336000D02*
X338500Y-97000D01*
X341000Y-105000D01*
G01X340100Y-102200D02*
X336900D01*
G01X346500Y-97000D02*
Y-105000D01*
G01X344200Y-97000D02*
X348800D01*
G01X352600Y-101667D02*
X353300Y-100733D01*
X353900Y-100200D01*
X354700Y-99933D01*
X355400Y-100200D01*
X355900Y-100733D01*
X356300Y-101533D01*
X356400Y-102467D01*
X356300Y-103267D01*
X355900Y-104067D01*
X355300Y-104733D01*
X354600Y-105000D01*
X353800Y-104733D01*
X353100Y-103934D01*
X352700Y-102733D01*
X352600Y-101400D01*
X352800Y-99667D01*
X353100Y-98733D01*
X353600Y-97800D01*
X354300Y-97133D01*
X355000Y-97000D01*
X355700Y-97267D01*
X356200Y-97933D01*
G01X359900Y-105000D02*
Y-97000D01*
X362500Y-103667D01*
X365100Y-97000D01*
Y-105000D01*
G01X370500Y-97000D02*
Y-105000D01*
G01X368200Y-97000D02*
X372800D01*
G01X379300Y-100733D02*
X379700Y-100333D01*
X380000Y-99667D01*
X380200Y-98733D01*
X380000Y-97933D01*
X379600Y-97400D01*
X378900Y-97000D01*
X376200D01*
Y-105000D01*
X379500D01*
X380200Y-104467D01*
X380600Y-103667D01*
X380800Y-102733D01*
X380600Y-101800D01*
X380000Y-101000D01*
X379300Y-100733D01*
X376200D01*
G01X386500Y-105000D02*
X387200Y-104867D01*
X388000Y-104467D01*
X388500Y-103800D01*
X388700Y-102867D01*
X388500Y-101934D01*
X387900Y-101133D01*
X387000Y-100733D01*
X386000D01*
X385400Y-100467D01*
X384900Y-99800D01*
X384700Y-98867D01*
X385000Y-97933D01*
X385700Y-97267D01*
X386500Y-97000D01*
X387300Y-97267D01*
X388000Y-97933D01*
X388300Y-98867D01*
X388100Y-99800D01*
X387600Y-100467D01*
X387000Y-100733D01*
X386000D01*
X385100Y-101133D01*
X384500Y-101934D01*
X384300Y-102867D01*
X384500Y-103800D01*
X385000Y-104467D01*
X385800Y-104867D01*
X386500Y-105000D01*
G01X394500D02*
X395200Y-104867D01*
X396000Y-104467D01*
X396500Y-103800D01*
X396700Y-102867D01*
X396500Y-101934D01*
X395900Y-101133D01*
X395000Y-100733D01*
X394000D01*
X393400Y-100467D01*
X392900Y-99800D01*
X392700Y-98867D01*
X393000Y-97933D01*
X393700Y-97267D01*
X394500Y-97000D01*
X395300Y-97267D01*
X396000Y-97933D01*
X396300Y-98867D01*
X396100Y-99800D01*
X395600Y-100467D01*
X395000Y-100733D01*
X394000D01*
X393100Y-101133D01*
X392500Y-101934D01*
X392300Y-102867D01*
X392500Y-103800D01*
X393000Y-104467D01*
X393800Y-104867D01*
X394500Y-105000D01*
G01X400000D02*
X402500Y-97000D01*
X405000Y-105000D01*
G01X404100Y-102200D02*
X400900D01*
G01X410500Y-97000D02*
X409700Y-97267D01*
X409100Y-97933D01*
X408700Y-98733D01*
X408400Y-99800D01*
X408300Y-101000D01*
X408400Y-102200D01*
X408700Y-103267D01*
X409100Y-104067D01*
X409700Y-104733D01*
X410500Y-105000D01*
X411300Y-104733D01*
X411900Y-104067D01*
X412300Y-103267D01*
X412600Y-102200D01*
X412700Y-101000D01*
X412600Y-99800D01*
X412300Y-98733D01*
X411900Y-97933D01*
X411300Y-97267D01*
X410500Y-97000D01*
G01X350500Y-72000D02*
Y-80000D01*
G01X348200Y-72000D02*
X352800D01*
G01X356600Y-76667D02*
X357300Y-75733D01*
X357900Y-75200D01*
X358700Y-74933D01*
X359400Y-75200D01*
X359900Y-75733D01*
X360300Y-76533D01*
X360400Y-77467D01*
X360300Y-78267D01*
X359900Y-79067D01*
X359300Y-79733D01*
X358600Y-80000D01*
X357800Y-79733D01*
X357100Y-78934D01*
X356700Y-77733D01*
X356600Y-76400D01*
X356800Y-74667D01*
X357100Y-73733D01*
X357600Y-72800D01*
X358300Y-72133D01*
X359000Y-72000D01*
X359700Y-72267D01*
X360200Y-72933D01*
G01X363900Y-80000D02*
Y-72000D01*
X366500Y-78667D01*
X369100Y-72000D01*
Y-80000D01*
G01X375100Y-76000D02*
X377100D01*
Y-78400D01*
X376500Y-79200D01*
X375800Y-79733D01*
X374800Y-80000D01*
X373800Y-79733D01*
X373100Y-79200D01*
X372500Y-78400D01*
X372100Y-77467D01*
X371900Y-76400D01*
Y-75467D01*
X372100Y-74667D01*
X372500Y-73733D01*
X373100Y-72933D01*
X373700Y-72400D01*
X374500Y-72000D01*
X375200D01*
X376000Y-72267D01*
X376600Y-72800D01*
G01X379500Y-82667D02*
X385500D01*
G01X388500Y-80000D02*
Y-72000D01*
X390900D01*
X391700Y-72400D01*
X392300Y-73333D01*
X392500Y-74400D01*
X392300Y-75467D01*
X391800Y-76267D01*
X390900Y-76667D01*
X388500D01*
G01X396300Y-80000D02*
Y-72000D01*
X398300D01*
X399100Y-72400D01*
X399700Y-72933D01*
X400200Y-73733D01*
X400600Y-74667D01*
X400700Y-76000D01*
X400600Y-77333D01*
X400200Y-78267D01*
X399700Y-79067D01*
X399100Y-79600D01*
X398300Y-80000D01*
X396300D01*
G01X407300Y-75733D02*
X407700Y-75333D01*
X408000Y-74667D01*
X408200Y-73733D01*
X408000Y-72933D01*
X407600Y-72400D01*
X406900Y-72000D01*
X404200D01*
Y-80000D01*
X407500D01*
X408200Y-79467D01*
X408600Y-78667D01*
X408800Y-77733D01*
X408600Y-76800D01*
X408000Y-76000D01*
X407300Y-75733D01*
X404200D01*
G01X411500Y-82667D02*
X417500D01*
G01X420000Y-80000D02*
X422500Y-72000D01*
X425000Y-80000D01*
G01X424100Y-77200D02*
X420900D01*
G01X427500Y-82667D02*
X433500D01*
G01X439300Y-75733D02*
X439700Y-75333D01*
X440000Y-74667D01*
X440200Y-73733D01*
X440000Y-72933D01*
X439600Y-72400D01*
X438900Y-72000D01*
X436200D01*
Y-80000D01*
X439500D01*
X440200Y-79467D01*
X440600Y-78667D01*
X440800Y-77733D01*
X440600Y-76800D01*
X440000Y-76000D01*
X439300Y-75733D01*
X436200D01*
G01X444300Y-80000D02*
Y-72000D01*
X446300D01*
X447100Y-72400D01*
X447700Y-72933D01*
X448200Y-73733D01*
X448600Y-74667D01*
X448700Y-76000D01*
X448600Y-77333D01*
X448200Y-78267D01*
X447700Y-79067D01*
X447100Y-79600D01*
X446300Y-80000D01*
X444300D01*
G01X443000Y-130000D02*
X445500Y-122000D01*
X448000Y-130000D01*
G01X447100Y-127200D02*
X443900D01*
G01X473000Y-130000D02*
Y-122000D01*
X471800Y-123600D01*
G01Y-130000D02*
X474200D01*
G01X479100Y-126667D02*
X479800Y-125733D01*
X480400Y-125200D01*
X481200Y-124933D01*
X481900Y-125200D01*
X482400Y-125733D01*
X482800Y-126533D01*
X482900Y-127467D01*
X482800Y-128267D01*
X482400Y-129067D01*
X481800Y-129733D01*
X481100Y-130000D01*
X480300Y-129733D01*
X479600Y-128934D01*
X479200Y-127733D01*
X479100Y-126400D01*
X479300Y-124667D01*
X479600Y-123733D01*
X480100Y-122800D01*
X480800Y-122133D01*
X481500Y-122000D01*
X482200Y-122267D01*
X482700Y-122933D01*
G54D22*
X72180Y675710D03*
Y680710D03*
Y685710D03*
Y690710D03*
X92980Y680710D03*
Y675710D03*
Y690710D03*
Y685710D03*
G54D13*
X14073Y512197D03*
Y522000D03*
Y552000D03*
Y561803D03*
Y1580004D03*
Y1570201D03*
Y1610004D03*
Y1619807D03*
X65254Y519500D03*
Y529500D03*
Y539500D03*
X55254Y524500D03*
Y534500D03*
X65254Y549500D03*
X55254Y544500D03*
X65254Y1577504D03*
Y1587504D03*
Y1597504D03*
X55254Y1582504D03*
Y1592504D03*
Y1602504D03*
X65254Y1607504D03*
G54D14*
X14691Y1559284D03*
X11541D03*
X54014Y904196D03*
X50864D03*
X54413Y1253378D03*
X51263D03*
X54210Y1263103D03*
X51060D03*
X54277Y1257633D03*
X51127D03*
X54582Y1279783D03*
X51432D03*
X54548Y1267290D03*
X51398D03*
X54446Y1284038D03*
X51296D03*
X54582Y1275630D03*
X51432D03*
X54481Y1271544D03*
X51331D03*
X59609Y1778371D03*
X62759D03*
X62637Y1782985D03*
X59487D03*
X86266Y1771103D03*
X83116D03*
X105845Y20080D03*
X108995D03*
X100778Y28320D03*
X103928D03*
X100693Y24203D03*
X103843D03*
X105845Y15847D03*
X108995D03*
X108090Y46285D03*
X104940D03*
X104932Y41803D03*
X108082D03*
X100778Y32853D03*
X103928D03*
X100778Y37438D03*
X103928D03*
X104137Y78186D03*
X107287D03*
X102727Y58250D03*
X105877D03*
X100518Y391220D03*
X103668D03*
X100518Y376580D03*
X103668D03*
X100518Y386235D03*
X103668D03*
X100518Y381386D03*
X103668D03*
X100518Y371909D03*
X103668D03*
X100518Y396024D03*
X103668D03*
X100794Y400352D03*
X103944D03*
X104518Y426104D03*
X107668D03*
X101056Y720745D03*
X104206D03*
X101056Y730398D03*
X104206D03*
X101056Y725457D03*
X104206D03*
X101056Y715937D03*
X104206D03*
X104346Y745139D03*
X101196D03*
X101056Y735248D03*
X104206D03*
X101056Y739962D03*
X104206D03*
X101520Y749481D03*
X104670D03*
X104442Y774100D03*
X107592D03*
X101189Y1067515D03*
X104339D03*
X101189Y1092036D03*
X104339D03*
X101189Y1072226D03*
X104339D03*
X101189Y1081791D03*
X104339D03*
X101189Y1076901D03*
X104339D03*
X101189Y1087095D03*
X104339D03*
X104432Y1096403D03*
X101282D03*
X105880Y1102535D03*
X109030D03*
X105684Y1122166D03*
X108834D03*
X100227Y1419492D03*
X103377D03*
X100227Y1429195D03*
X103377D03*
X100227Y1424340D03*
X103377D03*
X103443Y1447919D03*
X100293D03*
X100227Y1443743D03*
X103377D03*
X100227Y1434041D03*
X103377D03*
X100227Y1438980D03*
X103377D03*
X100019Y1453131D03*
X103169D03*
X105390Y1470205D03*
X108540D03*
X101677Y1760827D03*
X104827D03*
X101677Y1770527D03*
X104827D03*
X101677Y1765722D03*
X104827D03*
X104930Y1789947D03*
X101780D03*
X101677Y1785571D03*
X104827D03*
X101677Y1775514D03*
X104827D03*
X101677Y1780542D03*
X104827D03*
X105669Y1818228D03*
X108819D03*
X103671Y1798224D03*
X106821D03*
X159676Y56744D03*
X156526D03*
X158463Y68130D03*
X155313D03*
X155202Y72497D03*
X158352D03*
X158559Y88108D03*
X155409D03*
X158490Y407575D03*
X155340D03*
X158498Y436119D03*
X155348D03*
X158950Y756757D03*
X155800D03*
X158665Y764231D03*
X155515D03*
X155113Y776673D03*
X158263D03*
X158519Y784141D03*
X155369D03*
X159278Y1106853D03*
X156128D03*
X158497Y1132178D03*
X155347D03*
X160252Y1457084D03*
X157102D03*
X158976Y1480269D03*
X155826D03*
X159505Y1462651D03*
X156355D03*
X155648Y1473020D03*
X158798D03*
X158840Y1807740D03*
X155690D03*
X158563Y1815631D03*
X155413D03*
X158806Y1828225D03*
X155656D03*
X155409Y1820360D03*
X158559D03*
X184373Y937979D03*
X181223D03*
X184284Y943579D03*
X181134D03*
X184196Y962671D03*
X181046D03*
X184285Y957071D03*
X181135D03*
X184539Y973554D03*
X181389D03*
X184397Y990958D03*
X181247D03*
X184632Y979154D03*
X181482D03*
X184353Y996558D03*
X181203D03*
X184118Y1015313D03*
X180968D03*
X184115Y1009713D03*
X180965D03*
X182329Y1025022D03*
X179179D03*
X182327Y1030622D03*
X179177D03*
X264685Y128228D03*
X261535D03*
X264929Y115559D03*
X261779D03*
X264175Y823604D03*
X261025D03*
X264335Y812170D03*
X261185D03*
X272111Y463099D03*
X268961D03*
X272038Y473677D03*
X268888D03*
X288712Y1864565D03*
X285562D03*
X288794Y1858668D03*
X285644D03*
X308906Y1524401D03*
X305756D03*
X308636Y1513883D03*
X305486D03*
X320208Y1162266D03*
X317058D03*
X320264Y1172804D03*
X317114D03*
G54D23*
X56337Y878761D03*
X388591Y62106D03*
X385616Y1991570D03*
G54D24*
X74602Y1333203D03*
Y1328203D03*
Y1323203D03*
Y1318203D03*
X54130D03*
Y1323203D03*
Y1328203D03*
Y1333203D03*
G54D15*
X23402Y1668874D03*
Y1685410D03*
Y1701945D03*
Y1718480D03*
Y1735016D03*
Y1751551D03*
Y1768087D03*
Y1784622D03*
Y1817693D03*
Y1801158D03*
X45056Y1668874D03*
Y1685410D03*
Y1701945D03*
Y1718480D03*
Y1735016D03*
Y1751551D03*
Y1768087D03*
Y1784622D03*
Y1801158D03*
G54D25*
X60289Y1770835D03*
X67769D03*
X60289Y1762982D03*
X67769D03*
X60289Y1755171D03*
X67769D03*
X89071Y1748227D03*
X81591D03*
X87057Y1764190D03*
X79577D03*
G54D16*
X45411Y505996D03*
Y568004D03*
Y1564000D03*
Y1626008D03*
G54D26*
X70376Y1780543D03*
Y1801343D03*
X85376Y1780543D03*
X80376D03*
X75376D03*
Y1801343D03*
X80376D03*
X85376D03*
G54D17*
X45789Y896341D03*
X46023Y904215D03*
X48085Y919992D03*
X45981Y911910D03*
X47835Y960098D03*
X47109Y975598D03*
X48203Y1022325D03*
X47474Y1061692D03*
X47833Y1085626D03*
X47665Y1075692D03*
X47414Y1114586D03*
X47540Y1136770D03*
X46992Y1129235D03*
X47077Y1121658D03*
X46320Y1215867D03*
X49856Y1208711D03*
X45815Y1202354D03*
X46566Y1194825D03*
X46404Y1231610D03*
X45718Y1242795D03*
X49936Y1311343D03*
X65354Y101180D03*
X55511Y105117D03*
X51574Y114960D03*
X55511Y124803D03*
X65354Y128740D03*
Y451180D03*
X55511Y455117D03*
X51574Y464960D03*
X55511Y474803D03*
X65354Y478740D03*
Y801180D03*
X55511Y805117D03*
X51574Y814960D03*
X55511Y824803D03*
X65354Y828740D03*
X51149Y967593D03*
X51960Y953195D03*
X65354Y1151180D03*
X55511Y1155117D03*
X51574Y1164960D03*
X55511Y1174803D03*
X65354Y1178740D03*
X55496Y1235735D03*
X54654Y1244744D03*
X65354Y1501180D03*
X55511Y1505117D03*
X51574Y1514960D03*
X55511Y1524803D03*
X65354Y1528740D03*
X64356Y1788075D03*
X65354Y1851180D03*
X55511Y1855117D03*
X51574Y1864960D03*
X55511Y1874803D03*
X65354Y1878740D03*
X75197Y105117D03*
Y124803D03*
X79134Y114960D03*
Y464960D03*
X75197Y455117D03*
Y474803D03*
X93165Y706331D03*
X75197Y805117D03*
Y824803D03*
X79134Y814960D03*
Y1164960D03*
X75197Y1155117D03*
Y1174803D03*
X81341Y1310698D03*
X75197Y1505117D03*
Y1524803D03*
X79134Y1514960D03*
X75198Y1750574D03*
X92026Y1774879D03*
X79134Y1864960D03*
X75197Y1855117D03*
Y1874803D03*
X100595Y690710D03*
X307086Y113385D03*
X297243Y117322D03*
X293306Y127165D03*
X297243Y137008D03*
X307086Y140945D03*
Y463385D03*
X297243Y467322D03*
X293306Y477165D03*
X297243Y487008D03*
X307086Y490945D03*
Y813385D03*
X297243Y817322D03*
X293306Y827165D03*
X297243Y837008D03*
X307086Y840945D03*
Y1329724D03*
X297243Y1333661D03*
X293306Y1343504D03*
X297243Y1353347D03*
X307086Y1357284D03*
Y1679724D03*
X297243Y1683661D03*
X293306Y1693504D03*
X297243Y1703347D03*
X307086Y1707284D03*
X307087Y2029723D03*
X297244Y2033660D03*
X293307Y2043503D03*
X297244Y2053346D03*
X307087Y2057283D03*
X320866Y127165D03*
X316929Y117322D03*
Y137008D03*
Y467322D03*
Y487008D03*
X320866Y477165D03*
Y827165D03*
X316929Y817322D03*
Y837008D03*
Y1333661D03*
Y1353347D03*
X320866Y1343504D03*
Y1693504D03*
X316929Y1683661D03*
Y1703347D03*
X316930Y2033660D03*
Y2053346D03*
X320867Y2043503D03*
G54D27*
X87363Y708496D03*
X81563D03*
G54D18*
X45056Y1817693D03*
G54D19*
X64979Y35500D03*
Y45500D03*
Y55500D03*
X54979Y40500D03*
Y50500D03*
X64979Y65500D03*
X54979Y60500D03*
X64979Y171500D03*
X54979Y176500D03*
X64979Y181500D03*
Y191500D03*
Y201500D03*
X54979Y186500D03*
Y196500D03*
X64979Y244500D03*
X54979Y249500D03*
X64979Y254500D03*
Y264500D03*
Y274500D03*
X54979Y259500D03*
Y269500D03*
X64979Y380500D03*
Y390500D03*
X54979Y385500D03*
Y395500D03*
X64979Y400500D03*
Y410500D03*
X54979Y405500D03*
X189762Y73105D03*
X190289Y152050D03*
X190357Y247568D03*
X190817Y331786D03*
X189761Y421732D03*
X190553Y506517D03*
X192888Y598130D03*
X190816Y681645D03*
X191846Y774526D03*
X191606Y856244D03*
X196311Y947202D03*
X195516Y1032544D03*
X191250Y1122856D03*
X191342Y1206233D03*
X191846Y1299104D03*
X190552Y1380966D03*
X189463Y1474162D03*
X191079Y1557277D03*
X192143Y1648177D03*
X191607Y1731351D03*
X191530Y1823227D03*
X190289Y1900420D03*
X192125Y1998730D03*
X191530Y2043388D03*
G54D28*
X119920Y18071D03*
Y28071D03*
Y38071D03*
Y48071D03*
Y58071D03*
Y68071D03*
Y78071D03*
Y88071D03*
Y98071D03*
Y108071D03*
Y118071D03*
Y128071D03*
Y138071D03*
Y148071D03*
Y158071D03*
Y168071D03*
Y178071D03*
Y188071D03*
Y198071D03*
Y208071D03*
Y218071D03*
Y228071D03*
Y238071D03*
Y248071D03*
Y258071D03*
Y268071D03*
Y278071D03*
Y288071D03*
Y298071D03*
Y308071D03*
Y318071D03*
Y366102D03*
Y376102D03*
Y386102D03*
Y396102D03*
Y406102D03*
Y416102D03*
Y426102D03*
Y436102D03*
Y446102D03*
Y456102D03*
Y466102D03*
Y476102D03*
Y486102D03*
Y496102D03*
Y506102D03*
Y516102D03*
Y526102D03*
Y536102D03*
Y546102D03*
Y556102D03*
Y566102D03*
Y576102D03*
Y586102D03*
Y596102D03*
Y606102D03*
Y616102D03*
Y626102D03*
Y636102D03*
Y646102D03*
Y656102D03*
Y666102D03*
Y714134D03*
Y724134D03*
Y734134D03*
Y744134D03*
Y754134D03*
Y764134D03*
Y774134D03*
Y784134D03*
Y794134D03*
Y804134D03*
Y814134D03*
Y824134D03*
Y834134D03*
Y844134D03*
Y854134D03*
Y864134D03*
Y874134D03*
Y884134D03*
Y894134D03*
Y904134D03*
Y914134D03*
Y924134D03*
Y934134D03*
Y944134D03*
Y954134D03*
Y964134D03*
Y974134D03*
Y984134D03*
Y994134D03*
Y1004134D03*
Y1014134D03*
Y1062165D03*
Y1072165D03*
Y1082165D03*
Y1092165D03*
Y1102165D03*
Y1112165D03*
Y1122165D03*
Y1132165D03*
Y1142165D03*
Y1152165D03*
Y1162165D03*
Y1172165D03*
Y1182165D03*
Y1192165D03*
Y1202165D03*
Y1212165D03*
Y1222165D03*
Y1232165D03*
Y1242165D03*
Y1252165D03*
Y1262165D03*
Y1272165D03*
Y1282165D03*
Y1292165D03*
Y1302165D03*
Y1312165D03*
Y1322165D03*
Y1332165D03*
Y1342165D03*
Y1352165D03*
Y1362165D03*
Y1410197D03*
Y1420197D03*
Y1430197D03*
Y1440197D03*
Y1450197D03*
Y1460197D03*
Y1470197D03*
Y1480197D03*
Y1490197D03*
Y1500197D03*
Y1510197D03*
Y1520197D03*
Y1530197D03*
Y1540197D03*
Y1550197D03*
Y1560197D03*
Y1570197D03*
Y1580197D03*
Y1590197D03*
Y1600197D03*
Y1610197D03*
Y1620197D03*
Y1630197D03*
Y1640197D03*
Y1650197D03*
Y1660197D03*
Y1670197D03*
Y1680197D03*
Y1690197D03*
Y1700197D03*
Y1710197D03*
Y1758228D03*
Y1768228D03*
Y1778228D03*
Y1788228D03*
Y1798228D03*
Y1808228D03*
Y1818228D03*
Y1828228D03*
Y1838228D03*
Y1848228D03*
Y1858228D03*
Y1868228D03*
Y1878228D03*
Y1888228D03*
Y1898228D03*
Y1908228D03*
Y1918228D03*
Y1928228D03*
Y1938228D03*
Y1948228D03*
Y1958228D03*
Y1968228D03*
Y1978228D03*
Y1988228D03*
Y1998228D03*
Y2008228D03*
Y2018228D03*
Y2028228D03*
Y2038228D03*
Y2048228D03*
Y2058228D03*
X139920Y28071D03*
Y18071D03*
Y58071D03*
Y48071D03*
Y38071D03*
Y78071D03*
Y68071D03*
Y98071D03*
Y88071D03*
Y128071D03*
Y118071D03*
Y108071D03*
Y148071D03*
Y138071D03*
Y178071D03*
Y168071D03*
Y158071D03*
Y198071D03*
Y188071D03*
Y228071D03*
Y218071D03*
Y208071D03*
Y248071D03*
Y238071D03*
Y268071D03*
Y258071D03*
Y298071D03*
Y288071D03*
Y278071D03*
Y318071D03*
Y308071D03*
Y328071D03*
Y366102D03*
Y396102D03*
Y386102D03*
Y376102D03*
Y416102D03*
Y406102D03*
Y436102D03*
Y426102D03*
Y466102D03*
Y456102D03*
Y446102D03*
Y486102D03*
Y476102D03*
Y516102D03*
Y506102D03*
Y496102D03*
Y536102D03*
Y526102D03*
Y566102D03*
Y556102D03*
Y546102D03*
Y586102D03*
Y576102D03*
Y606102D03*
Y596102D03*
Y636102D03*
Y626102D03*
Y616102D03*
Y656102D03*
Y646102D03*
Y676102D03*
Y666102D03*
Y734134D03*
Y724134D03*
Y714134D03*
Y754134D03*
Y744134D03*
Y774134D03*
Y764134D03*
Y804134D03*
Y794134D03*
Y784134D03*
Y824134D03*
Y814134D03*
Y854134D03*
Y844134D03*
Y834134D03*
Y874134D03*
Y864134D03*
Y904134D03*
Y894134D03*
Y884134D03*
Y924134D03*
Y914134D03*
Y944134D03*
Y934134D03*
Y974134D03*
Y964134D03*
Y954134D03*
Y994134D03*
Y984134D03*
Y1024134D03*
Y1014134D03*
Y1004134D03*
Y1072165D03*
Y1062165D03*
Y1092165D03*
Y1082165D03*
Y1122165D03*
Y1112165D03*
Y1102165D03*
Y1142165D03*
Y1132165D03*
Y1162165D03*
Y1152165D03*
Y1192165D03*
Y1182165D03*
Y1172165D03*
Y1212165D03*
Y1202165D03*
Y1242165D03*
Y1232165D03*
Y1222165D03*
Y1262165D03*
Y1252165D03*
Y1282165D03*
Y1272165D03*
Y1312165D03*
Y1302165D03*
Y1292165D03*
Y1332165D03*
Y1322165D03*
Y1362165D03*
Y1352165D03*
Y1342165D03*
Y1372165D03*
Y1410197D03*
Y1430197D03*
Y1420197D03*
Y1460197D03*
Y1450197D03*
Y1440197D03*
Y1480197D03*
Y1470197D03*
Y1500197D03*
Y1490197D03*
Y1530197D03*
Y1520197D03*
Y1510197D03*
Y1550197D03*
Y1540197D03*
Y1580197D03*
Y1570197D03*
Y1560197D03*
Y1600197D03*
Y1590197D03*
Y1620197D03*
Y1610197D03*
Y1650197D03*
Y1640197D03*
Y1630197D03*
Y1670197D03*
Y1660197D03*
Y1700197D03*
Y1690197D03*
Y1680197D03*
Y1720197D03*
Y1710197D03*
Y1768228D03*
Y1758228D03*
Y1798228D03*
Y1788228D03*
Y1778228D03*
Y1818228D03*
Y1808228D03*
Y1838228D03*
Y1828228D03*
Y1868228D03*
Y1858228D03*
Y1848228D03*
Y1888228D03*
Y1878228D03*
Y1918228D03*
Y1908228D03*
Y1898228D03*
Y1938228D03*
Y1928228D03*
Y1958228D03*
Y1948228D03*
Y1988228D03*
Y1978228D03*
Y1968228D03*
Y2008228D03*
Y1998228D03*
Y2038228D03*
Y2028228D03*
Y2018228D03*
Y2058228D03*
Y2048228D03*
Y2068228D03*
G54D29*
X119920Y328071D03*
Y676102D03*
Y1024134D03*
Y1372165D03*
Y1720197D03*
Y2068228D03*
M02*
